(kicad_pcb
	(version 20260206)
	(generator "pcbnew")
	(generator_version "10.0")
	(general
		(thickness 1.6)
		(legacy_teardrops no)
	)
	(paper "A4")
	(title_block
		(title "01162023_DA0F0TEBIF0_F0T_Expander_BD_F_brd_V02_OCP.brd")
		(comment 1 "Grand Teton / footprints 2529-2534 of 9728")
	)
	(layers
		(0 "F.Cu" signal "TOP")
		(4 "In1.Cu" signal "GND")
		(6 "In2.Cu" signal "VCC")
		(8 "In3.Cu" signal "VCC1")
		(10 "In4.Cu" signal "GND1")
		(12 "In5.Cu" signal "IN1")
		(14 "In6.Cu" signal "GND2")
		(16 "In7.Cu" signal "IN2")
		(18 "In8.Cu" signal "GND3")
		(20 "In9.Cu" signal "IN3")
		(22 "In10.Cu" signal "GND4")
		(24 "In11.Cu" signal "IN4")
		(26 "In12.Cu" signal "GND5")
		(28 "In13.Cu" signal "IN5")
		(30 "In14.Cu" signal "GND6")
		(32 "In15.Cu" signal "IN6")
		(34 "In16.Cu" signal "GND7")
		(2 "B.Cu" signal "BOTTOM")
		(9 "F.Adhes" user "F.Adhesive")
		(11 "B.Adhes" user "B.Adhesive")
		(13 "F.Paste" user "Package Geometry/Pastemask Top")
		(15 "B.Paste" user "Package Geometry/Pastemask Bottom")
		(5 "F.SilkS" user "Ref Des/Silkscreen Top")
		(7 "B.SilkS" user "Ref Des/Silkscreen Bottom")
		(1 "F.Mask" user "Board Geometry/Soldermask Top")
		(3 "B.Mask" user "Board Geometry/Soldermask Bottom")
		(17 "Dwgs.User" user "User.Drawings")
		(19 "Cmts.User" user "User.Comments")
		(21 "Eco1.User" user "User.Eco1")
		(23 "Eco2.User" user "User.Eco2")
		(25 "Edge.Cuts" user "Board Geometry/Outline")
		(27 "Margin" user)
		(31 "F.CrtYd" user "Package Geometry/Place Bound Top")
		(29 "B.CrtYd" user "Package Geometry/Place Bound Bottom")
		(35 "F.Fab" user "Ref Des/Assembly Top")
		(33 "B.Fab" user "Ref Des/Assembly Bottom")
	)
	(footprint ""
		(layer "F.Cu")
		(at 452.909178 -109.432598 -90)
		(property "Reference" "PC827"
			(at 0 0 270)
			(layer "F.SilkS")
			(hide yes)
			(effects
				(font
					(size 1.27 1.27)
				)
			)
		)
		(property "Value" ""
			(at 0 0 270)
			(layer "F.Fab")
			(effects
				(font
					(size 1.27 1.27)
				)
			)
		)
		(duplicate_pad_numbers_are_jumpers no)
		(fp_line
			(start -0.7874 0.4064)
			(end -0.7874 -0.4064)
			(stroke
				(width 0.1524)
				(type default)
			)
			(layer "F.SilkS")
		)
		(fp_line
			(start 0.7874 0.4064)
			(end -0.7874 0.4064)
			(stroke
				(width 0.1524)
				(type default)
			)
			(layer "F.SilkS")
		)
		(fp_line
			(start -0.7874 -0.4064)
			(end 0.7874 -0.4064)
			(stroke
				(width 0.1524)
				(type default)
			)
			(layer "F.SilkS")
		)
		(fp_line
			(start 0.7874 -0.4064)
			(end 0.7874 0.4064)
			(stroke
				(width 0.1524)
				(type default)
			)
			(layer "F.SilkS")
		)
		(fp_line
			(start -0.67945 0.3048)
			(end -0.67945 -0.305054)
			(stroke
				(width 0.1)
				(type default)
			)
			(layer "F.Fab")
		)
		(fp_line
			(start -0.12065 0.3048)
			(end -0.67945 0.3048)
			(stroke
				(width 0.1)
				(type default)
			)
			(layer "F.Fab")
		)
		(fp_line
			(start 0.120396 0.3048)
			(end 0.120396 0.2794)
			(stroke
				(width 0.1)
				(type default)
			)
			(layer "F.Fab")
		)
		(fp_line
			(start 0.67945 0.3048)
			(end 0.120396 0.3048)
			(stroke
				(width 0.1)
				(type default)
			)
			(layer "F.Fab")
		)
		(fp_line
			(start -0.12065 0.2794)
			(end -0.12065 0.3048)
			(stroke
				(width 0.1)
				(type default)
			)
			(layer "F.Fab")
		)
		(fp_line
			(start 0.120396 0.2794)
			(end -0.12065 0.2794)
			(stroke
				(width 0.1)
				(type default)
			)
			(layer "F.Fab")
		)
		(fp_line
			(start -0.12065 -0.2794)
			(end 0.12065 -0.2794)
			(stroke
				(width 0.1)
				(type default)
			)
			(layer "F.Fab")
		)
		(fp_line
			(start 0.12065 -0.2794)
			(end 0.12065 -0.3048)
			(stroke
				(width 0.1)
				(type default)
			)
			(layer "F.Fab")
		)
		(fp_line
			(start 0.12065 -0.3048)
			(end 0.67945 -0.3048)
			(stroke
				(width 0.1)
				(type default)
			)
			(layer "F.Fab")
		)
		(fp_line
			(start 0.67945 -0.3048)
			(end 0.67945 0.3048)
			(stroke
				(width 0.1)
				(type default)
			)
			(layer "F.Fab")
		)
		(fp_line
			(start -0.67945 -0.305054)
			(end -0.12065 -0.305054)
			(stroke
				(width 0.1)
				(type default)
			)
			(layer "F.Fab")
		)
		(fp_line
			(start -0.12065 -0.305054)
			(end -0.12065 -0.2794)
			(stroke
				(width 0.1)
				(type default)
			)
			(layer "F.Fab")
		)
		(pad "1" smd circle
			(at -0.40005 0 270)
			(size 0 0)
			(layers "F.Cu" "F.Mask" "F.Paste")
			(net "P12V_NIC7_R")
		)
		(pad "2" smd circle
			(at 0.40005 0 270)
			(size 0 0)
			(layers "F.Cu" "F.Mask" "F.Paste")
			(net "GND")
		)
	)
	(footprint ""
		(layer "F.Cu")
		(at 260.12521 -338.426806 90)
		(property "Reference" "C4486"
			(at 0 0 90)
			(layer "F.SilkS")
			(hide yes)
			(effects
				(font
					(size 1.27 1.27)
				)
			)
		)
		(property "Value" ""
			(at 0 0 90)
			(layer "F.Fab")
			(effects
				(font
					(size 1.27 1.27)
				)
			)
		)
		(duplicate_pad_numbers_are_jumpers no)
		(fp_line
			(start 0.7874 -0.4064)
			(end 0.7874 0.4064)
			(stroke
				(width 0.1524)
				(type default)
			)
			(layer "F.SilkS")
		)
		(fp_line
			(start -0.7874 -0.4064)
			(end 0.7874 -0.4064)
			(stroke
				(width 0.1524)
				(type default)
			)
			(layer "F.SilkS")
		)
		(fp_line
			(start 0.7874 0.4064)
			(end -0.7874 0.4064)
			(stroke
				(width 0.1524)
				(type default)
			)
			(layer "F.SilkS")
		)
		(fp_line
			(start -0.7874 0.4064)
			(end -0.7874 -0.4064)
			(stroke
				(width 0.1524)
				(type default)
			)
			(layer "F.SilkS")
		)
		(fp_line
			(start -0.12065 -0.305054)
			(end -0.12065 -0.2794)
			(stroke
				(width 0.1)
				(type default)
			)
			(layer "F.Fab")
		)
		(fp_line
			(start -0.67945 -0.305054)
			(end -0.12065 -0.305054)
			(stroke
				(width 0.1)
				(type default)
			)
			(layer "F.Fab")
		)
		(fp_line
			(start 0.67945 -0.3048)
			(end 0.67945 0.3048)
			(stroke
				(width 0.1)
				(type default)
			)
			(layer "F.Fab")
		)
		(fp_line
			(start 0.12065 -0.3048)
			(end 0.67945 -0.3048)
			(stroke
				(width 0.1)
				(type default)
			)
			(layer "F.Fab")
		)
		(fp_line
			(start 0.12065 -0.2794)
			(end 0.12065 -0.3048)
			(stroke
				(width 0.1)
				(type default)
			)
			(layer "F.Fab")
		)
		(fp_line
			(start -0.12065 -0.2794)
			(end 0.12065 -0.2794)
			(stroke
				(width 0.1)
				(type default)
			)
			(layer "F.Fab")
		)
		(fp_line
			(start 0.120396 0.2794)
			(end -0.12065 0.2794)
			(stroke
				(width 0.1)
				(type default)
			)
			(layer "F.Fab")
		)
		(fp_line
			(start -0.12065 0.2794)
			(end -0.12065 0.3048)
			(stroke
				(width 0.1)
				(type default)
			)
			(layer "F.Fab")
		)
		(fp_line
			(start 0.67945 0.3048)
			(end 0.120396 0.3048)
			(stroke
				(width 0.1)
				(type default)
			)
			(layer "F.Fab")
		)
		(fp_line
			(start 0.120396 0.3048)
			(end 0.120396 0.2794)
			(stroke
				(width 0.1)
				(type default)
			)
			(layer "F.Fab")
		)
		(fp_line
			(start -0.12065 0.3048)
			(end -0.67945 0.3048)
			(stroke
				(width 0.1)
				(type default)
			)
			(layer "F.Fab")
		)
		(fp_line
			(start -0.67945 0.3048)
			(end -0.67945 -0.305054)
			(stroke
				(width 0.1)
				(type default)
			)
			(layer "F.Fab")
		)
		(pad "1" smd circle
			(at -0.40005 0 90)
			(size 0 0)
			(layers "F.Cu" "F.Mask" "F.Paste")
			(net "OC_P2V5_COMP")
		)
		(pad "2" smd circle
			(at 0.40005 0 90)
			(size 0 0)
			(layers "F.Cu" "F.Mask" "F.Paste")
			(net "GND")
		)
	)
	(footprint ""
		(layer "F.Cu")
		(at 219.014294 -178.09718)
		(property "Reference" "R5781"
			(at 0 0 0)
			(layer "F.SilkS")
			(hide yes)
			(effects
				(font
					(size 1.27 1.27)
				)
			)
		)
		(property "Value" ""
			(at 0 0 0)
			(layer "F.Fab")
			(effects
				(font
					(size 1.27 1.27)
				)
			)
		)
		(duplicate_pad_numbers_are_jumpers no)
		(fp_line
			(start -0.7874 -0.4064)
			(end 0.7874 -0.4064)
			(stroke
				(width 0.1524)
				(type default)
			)
			(layer "F.SilkS")
		)
		(fp_line
			(start -0.7874 0.4064)
			(end -0.7874 -0.4064)
			(stroke
				(width 0.1524)
				(type default)
			)
			(layer "F.SilkS")
		)
		(fp_line
			(start 0.7874 -0.4064)
			(end 0.7874 0.4064)
			(stroke
				(width 0.1524)
				(type default)
			)
			(layer "F.SilkS")
		)
		(fp_line
			(start 0.7874 0.4064)
			(end -0.7874 0.4064)
			(stroke
				(width 0.1524)
				(type default)
			)
			(layer "F.SilkS")
		)
		(fp_line
			(start -0.67945 -0.305054)
			(end -0.12065 -0.305054)
			(stroke
				(width 0.1)
				(type default)
			)
			(layer "F.Fab")
		)
		(fp_line
			(start -0.67945 0.3048)
			(end -0.67945 -0.305054)
			(stroke
				(width 0.1)
				(type default)
			)
			(layer "F.Fab")
		)
		(fp_line
			(start -0.12065 -0.305054)
			(end -0.12065 -0.2794)
			(stroke
				(width 0.1)
				(type default)
			)
			(layer "F.Fab")
		)
		(fp_line
			(start -0.12065 -0.2794)
			(end 0.12065 -0.2794)
			(stroke
				(width 0.1)
				(type default)
			)
			(layer "F.Fab")
		)
		(fp_line
			(start -0.12065 0.2794)
			(end -0.12065 0.3048)
			(stroke
				(width 0.1)
				(type default)
			)
			(layer "F.Fab")
		)
		(fp_line
			(start -0.12065 0.3048)
			(end -0.67945 0.3048)
			(stroke
				(width 0.1)
				(type default)
			)
			(layer "F.Fab")
		)
		(fp_line
			(start 0.120396 0.2794)
			(end -0.12065 0.2794)
			(stroke
				(width 0.1)
				(type default)
			)
			(layer "F.Fab")
		)
		(fp_line
			(start 0.120396 0.3048)
			(end 0.120396 0.2794)
			(stroke
				(width 0.1)
				(type default)
			)
			(layer "F.Fab")
		)
		(fp_line
			(start 0.12065 -0.3048)
			(end 0.67945 -0.3048)
			(stroke
				(width 0.1)
				(type default)
			)
			(layer "F.Fab")
		)
		(fp_line
			(start 0.12065 -0.2794)
			(end 0.12065 -0.3048)
			(stroke
				(width 0.1)
				(type default)
			)
			(layer "F.Fab")
		)
		(fp_line
			(start 0.67945 -0.3048)
			(end 0.67945 0.3048)
			(stroke
				(width 0.1)
				(type default)
			)
			(layer "F.Fab")
		)
		(fp_line
			(start 0.67945 0.3048)
			(end 0.120396 0.3048)
			(stroke
				(width 0.1)
				(type default)
			)
			(layer "F.Fab")
		)
		(pad "1" smd circle
			(at -0.40005 0)
			(size 0 0)
			(layers "F.Cu" "F.Mask" "F.Paste")
			(net "P3V3_AUX")
		)
		(pad "2" smd circle
			(at 0.40005 0)
			(size 0 0)
			(layers "F.Cu" "F.Mask" "F.Paste")
			(net "RST_FW_BIC_PLTRST")
		)
	)
	(footprint ""
		(layer "F.Cu")
		(at 262.281924 -289.790632 180)
		(property "Reference" "C3397"
			(at 0 0 180)
			(layer "F.SilkS")
			(hide yes)
			(effects
				(font
					(size 1.27 1.27)
				)
			)
		)
		(property "Value" ""
			(at 0 0 180)
			(layer "F.Fab")
			(effects
				(font
					(size 1.27 1.27)
				)
			)
		)
		(duplicate_pad_numbers_are_jumpers no)
		(fp_line
			(start 1.2954 0.5842)
			(end -1.2954 0.5842)
			(stroke
				(width 0.1524)
				(type default)
			)
			(layer "F.SilkS")
		)
		(fp_line
			(start 1.2954 -0.5842)
			(end 1.2954 0.5842)
			(stroke
				(width 0.1524)
				(type default)
			)
			(layer "F.SilkS")
		)
		(fp_line
			(start -1.2954 0.5842)
			(end -1.2954 -0.5842)
			(stroke
				(width 0.1524)
				(type default)
			)
			(layer "F.SilkS")
		)
		(fp_line
			(start -1.2954 -0.5842)
			(end 1.2954 -0.5842)
			(stroke
				(width 0.1524)
				(type default)
			)
			(layer "F.SilkS")
		)
		(fp_line
			(start 1.1938 0.4064)
			(end 0.8636 0.4064)
			(stroke
				(width 0.1)
				(type default)
			)
			(layer "F.Fab")
		)
		(fp_line
			(start 1.1938 -0.4064)
			(end 1.1938 0.4064)
			(stroke
				(width 0.1)
				(type default)
			)
			(layer "F.Fab")
		)
		(fp_line
			(start 0.8636 0.4572)
			(end -0.8636 0.4572)
			(stroke
				(width 0.1)
				(type default)
			)
			(layer "F.Fab")
		)
		(fp_line
			(start 0.8636 0.4064)
			(end 0.8636 0.4572)
			(stroke
				(width 0.1)
				(type default)
			)
			(layer "F.Fab")
		)
		(fp_line
			(start 0.8636 -0.4064)
			(end 1.1938 -0.4064)
			(stroke
				(width 0.1)
				(type default)
			)
			(layer "F.Fab")
		)
		(fp_line
			(start 0.8636 -0.4572)
			(end 0.8636 -0.4064)
			(stroke
				(width 0.1)
				(type default)
			)
			(layer "F.Fab")
		)
		(fp_line
			(start -0.8636 0.4572)
			(end -0.8636 0.4064)
			(stroke
				(width 0.1)
				(type default)
			)
			(layer "F.Fab")
		)
		(fp_line
			(start -0.8636 0.4064)
			(end -1.1938 0.4064)
			(stroke
				(width 0.1)
				(type default)
			)
			(layer "F.Fab")
		)
		(fp_line
			(start -0.8636 -0.4064)
			(end -0.8636 -0.4572)
			(stroke
				(width 0.1)
				(type default)
			)
			(layer "F.Fab")
		)
		(fp_line
			(start -0.8636 -0.4572)
			(end 0.8636 -0.4572)
			(stroke
				(width 0.1)
				(type default)
			)
			(layer "F.Fab")
		)
		(fp_line
			(start -1.1938 0.4064)
			(end -1.1938 -0.4064)
			(stroke
				(width 0.1)
				(type default)
			)
			(layer "F.Fab")
		)
		(fp_line
			(start -1.1938 -0.4064)
			(end -0.8636 -0.4064)
			(stroke
				(width 0.1)
				(type default)
			)
			(layer "F.Fab")
		)
		(pad "1" smd rect
			(at -0.7366 0 90)
			(size 0.7112 0.8128)
			(layers "F.Cu" "F.Mask" "F.Paste")
			(net "PCEPLL4_VDDA18_PEX2_R")
		)
		(pad "2" smd rect
			(at 0.7366 0 90)
			(size 0.7112 0.8128)
			(layers "F.Cu" "F.Mask" "F.Paste")
			(net "GND")
		)
	)
	(footprint ""
		(layer "F.Cu")
		(at 261.528306 -77.279754 -90)
		(property "Reference" "R1078"
			(at 0 0 270)
			(layer "F.SilkS")
			(hide yes)
			(effects
				(font
					(size 1.27 1.27)
				)
			)
		)
		(property "Value" ""
			(at 0 0 270)
			(layer "F.Fab")
			(effects
				(font
					(size 1.27 1.27)
				)
			)
		)
		(duplicate_pad_numbers_are_jumpers no)
		(fp_line
			(start -0.7874 0.4064)
			(end -0.7874 -0.4064)
			(stroke
				(width 0.1524)
				(type default)
			)
			(layer "F.SilkS")
		)
		(fp_line
			(start 0.7874 0.4064)
			(end -0.7874 0.4064)
			(stroke
				(width 0.1524)
				(type default)
			)
			(layer "F.SilkS")
		)
		(fp_line
			(start -0.7874 -0.4064)
			(end 0.7874 -0.4064)
			(stroke
				(width 0.1524)
				(type default)
			)
			(layer "F.SilkS")
		)
		(fp_line
			(start 0.7874 -0.4064)
			(end 0.7874 0.4064)
			(stroke
				(width 0.1524)
				(type default)
			)
			(layer "F.SilkS")
		)
		(fp_line
			(start -0.67945 0.3048)
			(end -0.67945 -0.305054)
			(stroke
				(width 0.1)
				(type default)
			)
			(layer "F.Fab")
		)
		(fp_line
			(start -0.12065 0.3048)
			(end -0.67945 0.3048)
			(stroke
				(width 0.1)
				(type default)
			)
			(layer "F.Fab")
		)
		(fp_line
			(start 0.120396 0.3048)
			(end 0.120396 0.2794)
			(stroke
				(width 0.1)
				(type default)
			)
			(layer "F.Fab")
		)
		(fp_line
			(start 0.67945 0.3048)
			(end 0.120396 0.3048)
			(stroke
				(width 0.1)
				(type default)
			)
			(layer "F.Fab")
		)
		(fp_line
			(start -0.12065 0.2794)
			(end -0.12065 0.3048)
			(stroke
				(width 0.1)
				(type default)
			)
			(layer "F.Fab")
		)
		(fp_line
			(start 0.120396 0.2794)
			(end -0.12065 0.2794)
			(stroke
				(width 0.1)
				(type default)
			)
			(layer "F.Fab")
		)
		(fp_line
			(start -0.12065 -0.2794)
			(end 0.12065 -0.2794)
			(stroke
				(width 0.1)
				(type default)
			)
			(layer "F.Fab")
		)
		(fp_line
			(start 0.12065 -0.2794)
			(end 0.12065 -0.3048)
			(stroke
				(width 0.1)
				(type default)
			)
			(layer "F.Fab")
		)
		(fp_line
			(start 0.12065 -0.3048)
			(end 0.67945 -0.3048)
			(stroke
				(width 0.1)
				(type default)
			)
			(layer "F.Fab")
		)
		(fp_line
			(start 0.67945 -0.3048)
			(end 0.67945 0.3048)
			(stroke
				(width 0.1)
				(type default)
			)
			(layer "F.Fab")
		)
		(fp_line
			(start -0.67945 -0.305054)
			(end -0.12065 -0.305054)
			(stroke
				(width 0.1)
				(type default)
			)
			(layer "F.Fab")
		)
		(fp_line
			(start -0.12065 -0.305054)
			(end -0.12065 -0.2794)
			(stroke
				(width 0.1)
				(type default)
			)
			(layer "F.Fab")
		)
		(pad "1" smd circle
			(at -0.40005 0 270)
			(size 0 0)
			(layers "F.Cu" "F.Mask" "F.Paste")
			(net "CLK_GEN_CK440_OE3_N")
		)
		(pad "2" smd circle
			(at 0.40005 0 270)
			(size 0 0)
			(layers "F.Cu" "F.Mask" "F.Paste")
			(net "P3V3")
		)
	)
	(footprint ""
		(layer "F.Cu")
		(at 331.07376 -103.668068)
		(property "Reference" "PC806"
			(at 0 0 0)
			(layer "F.SilkS")
			(hide yes)
			(effects
				(font
					(size 1.27 1.27)
				)
			)
		)
		(property "Value" ""
			(at 0 0 0)
			(layer "F.Fab")
			(effects
				(font
					(size 1.27 1.27)
				)
			)
		)
		(duplicate_pad_numbers_are_jumpers no)
		(fp_line
			(start -1.524 -0.762)
			(end 1.524 -0.762)
			(stroke
				(width 0.1524)
				(type default)
			)
			(layer "F.SilkS")
		)
		(fp_line
			(start -1.524 0.762)
			(end -1.524 -0.762)
			(stroke
				(width 0.1524)
				(type default)
			)
			(layer "F.SilkS")
		)
		(fp_line
			(start 1.524 -0.762)
			(end 1.524 0.762)
			(stroke
				(width 0.1524)
				(type default)
			)
			(layer "F.SilkS")
		)
		(fp_line
			(start 1.524 0.762)
			(end -1.524 0.762)
			(stroke
				(width 0.1524)
				(type default)
			)
			(layer "F.SilkS")
		)
		(fp_line
			(start -1.1049 -0.724916)
			(end -1.1049 0.724916)
			(stroke
				(width 0.1)
				(type default)
			)
			(layer "F.Fab")
		)
		(fp_line
			(start -1.1049 0.724916)
			(end 1.1049 0.724916)
			(stroke
				(width 0.1)
				(type default)
			)
			(layer "F.Fab")
		)
		(fp_line
			(start 1.1049 -0.724916)
			(end -1.1049 -0.724916)
			(stroke
				(width 0.1)
				(type default)
			)
			(layer "F.Fab")
		)
		(fp_line
			(start 1.1049 0.724916)
			(end 1.1049 -0.724916)
			(stroke
				(width 0.1)
				(type default)
			)
			(layer "F.Fab")
		)
		(pad "1" smd rect
			(at -0.889 0 180)
			(size 1.016 1.27)
			(layers "F.Cu" "F.Mask" "F.Paste")
			(net "P12V_NIC5_R")
		)
		(pad "2" smd rect
			(at 0.889 0 180)
			(size 1.016 1.27)
			(layers "F.Cu" "F.Mask" "F.Paste")
			(net "GND")
		)
	)
)
